FILE_TYPE = MULTI_PHYS_TABLE;

PART '74LVC1G07SE7'

{========================================================================================}
:VALUE           | PART_TYPE | MATERIAL | PART_NUMBER    = STANDARD    | LIFECYCLE      | PART_NUMBER   | JEDEC_TYPE           | DESCRIPTION                         | MANUFTR | MANUF_PN        | RD_CMPLS_LVL | CMPLS_LVL | FROM_PJ    | CLASS | DIP_SMD | DATA                    | EE_CHECK_LIST | FP_ECN | PSL | CREATOR | STATUS | MSD | ESD_CDM | ESD_HBM | ESD_MM | PIN_LENGTH_SHORT_PIN | PIN_LENGTH_LONG_PIN | CREATEDAY  ;
{========================================================================================}
 '74LVC1G07SE-7' | 'SMLF'    | 'IC'     | 'AL1G07SE000'(!) = ''               | ''               | 'AL1G07SE000' |'SOT353_0-65_2X1-25'| 'IC OTHER(5P)74LVC1G07SE-7(SOT353)' | 'DDS'   | '74LVC1G07SE-7' | 'EP(V1)'     | 'EP(V1)'  | 'F0C-IVES' | 'IC'  | ''      | 'DDS_74LVC1G07SE-7.pdf' | ''            | ''     | ''  | ''      | ''     | ''  | ''      | ''      | ''     | '0 MILS'             | '0 MILS'            | '20210615'
 '74LVC1G07SE-7' | 'SMLF'    | 'EMPTY'  | 'AL1G07SE000'(!) = ''               | ''               | 'AL1G07SE000' |'SOT353_0-65_2X1-25'| 'IC OTHER(5P)74LVC1G07SE-7(SOT353)' | 'DDS'   | '74LVC1G07SE-7' | 'EP(V1)'     | 'EP(V1)'  | 'F0C-IVES' | 'IC'  | ''      | 'DDS_74LVC1G07SE-7.pdf' | ''            | ''     | ''  | ''      | ''     | ''  | ''      | ''      | ''     | '0 MILS'             | '0 MILS'            | '20210615'

END_PART

END.

